(kicad_pcb
	(version 20260206)
	(generator "pcbnew")
	(generator_version "10.0")
	(general
		(thickness 1.6)
		(legacy_teardrops no)
	)
	(paper "A4")
	(title_block
		(title "netronome-mezz — pcbd0082-001_rev01_jul9_a.brd")
		(comment 1 "Open CloudServer (Microsoft) / footprints 226-234 of 714")
	)
	(layers
		(0 "F.Cu" signal "TOP")
		(4 "In1.Cu" signal "02_GND")
		(6 "In2.Cu" signal "03_SIG")
		(8 "In3.Cu" signal "04_SIG")
		(10 "In4.Cu" signal "05_GND")
		(12 "In5.Cu" signal "06_PWR1")
		(14 "In6.Cu" signal "07_SIG")
		(16 "In7.Cu" signal "08_SIG")
		(18 "In8.Cu" signal "09_GND")
		(2 "B.Cu" signal "BOTTOM")
		(9 "F.Adhes" user "F.Adhesive")
		(11 "B.Adhes" user "B.Adhesive")
		(13 "F.Paste" user "Package Geometry/Pastemask Top")
		(15 "B.Paste" user "Package Geometry/Pastemask Bottom")
		(5 "F.SilkS" user "Ref Des/Silkscreen Top")
		(7 "B.SilkS" user "Ref Des/Silkscreen Bottom")
		(1 "F.Mask" user "Board Geometry/Soldermask Top")
		(3 "B.Mask" user "Board Geometry/Soldermask Bottom")
		(17 "Dwgs.User" user "User.Drawings")
		(19 "Cmts.User" user "User.Comments")
		(21 "Eco1.User" user "User.Eco1")
		(23 "Eco2.User" user "User.Eco2")
		(25 "Edge.Cuts" user "Board Geometry/Outline")
		(27 "Margin" user)
		(31 "F.CrtYd" user "Package Geometry/Place Bound Top")
		(29 "B.CrtYd" user "Package Geometry/Place Bound Bottom")
		(35 "F.Fab" user "Ref Des/Assembly Top")
		(33 "B.Fab" user "Ref Des/Assembly Bottom")
		(45 "User.4" user "COMPVAL_TYPE_BOTTOM")
	)
	(footprint ""
		(layer "F.Cu")
		(at 21.971 16.8529)
		(property "Reference" "R21"
			(at 0 0 0)
			(layer "F.SilkS")
			(hide yes)
			(effects
				(font
					(size 1.27 1.27)
				)
			)
		)
		(property "Value" "4.75K"
			(at -0.148158 1.3462 90)
			(unlocked yes)
			(layer "F.Fab")
			(hide yes)
			(effects
				(font
					(size 1.27 0.9652)
					(thickness 0.000001)
				)
				(justify left)
			)
		)
		(property "Device Type" "REST4024"
			(at -0.148158 1.3462 90)
			(unlocked yes)
			(layer "F.Fab")
			(hide yes)
			(effects
				(font
					(size 1.27 0.9652)
					(thickness 0.000001)
				)
				(justify left)
			)
		)
		(duplicate_pad_numbers_are_jumpers no)
		(fp_poly
			(pts
				(xy 0.635 1.0668) (xy 0.635 -1.0668) (xy -0.635 -1.0668) (xy -0.635 1.0668)
			)
			(stroke
				(width 0)
				(type default)
			)
			(fill no)
			(layer "F.CrtYd")
		)
		(fp_line
			(start -0.254 -0.508)
			(end 0.254 -0.508)
			(stroke
				(width 0.0254)
				(type default)
			)
			(layer "F.Fab")
		)
		(fp_line
			(start -0.254 0.508)
			(end -0.254 -0.508)
			(stroke
				(width 0.0254)
				(type default)
			)
			(layer "F.Fab")
		)
		(fp_line
			(start 0.254 -0.508)
			(end 0.254 0.508)
			(stroke
				(width 0.0254)
				(type default)
			)
			(layer "F.Fab")
		)
		(fp_line
			(start 0.254 0.508)
			(end -0.254 0.508)
			(stroke
				(width 0.0254)
				(type default)
			)
			(layer "F.Fab")
		)
		(pad "1" smd rect
			(at 0 -0.4191)
			(size 0.508 0.5334)
			(layers "F.Cu" "F.Mask" "F.Paste")
			(net "VDD_3.3V")
		)
		(pad "2" smd rect
			(at 0 0.4191)
			(size 0.508 0.5334)
			(layers "F.Cu" "F.Mask" "F.Paste")
			(net "3N2521")
		)
		(zone
			(layer "F.Cu")
			(hatch none 0.5)
			(connect_pads
				(clearance 0)
			)
			(min_thickness 0.25)
			(keepout
				(tracks not_allowed)
				(vias allowed)
				(pads allowed)
				(copperpour not_allowed)
				(footprints allowed)
			)
			(placement
				(enabled no)
				(sheetname "")
			)
			(fill
				(thermal_gap 0.5)
				(thermal_bridge_width 0.5)
				(island_removal_mode 0)
			)
			(polygon
				(pts
					(xy 21.9964 16.8275) (xy 21.9964 16.8783) (xy 21.9456 16.8783) (xy 21.9456 16.8275)
				)
			)
		)
	)
	(footprint ""
		(layer "F.Cu")
		(at 16.51 1.397)
		(property "Reference" "R396"
			(at 0.66167 -0.762 90)
			(unlocked yes)
			(layer "F.SilkS")
			(effects
				(font
					(size 0.7874 0.5842)
					(thickness 0.127)
				)
				(justify left)
			)
		)
		(property "Value" "4.75K"
			(at -0.148158 1.3462 90)
			(unlocked yes)
			(layer "F.Fab")
			(hide yes)
			(effects
				(font
					(size 1.27 0.9652)
					(thickness 0.000001)
				)
				(justify left)
			)
		)
		(property "Device Type" "REST4024"
			(at -0.148158 1.3462 90)
			(unlocked yes)
			(layer "F.Fab")
			(hide yes)
			(effects
				(font
					(size 1.27 0.9652)
					(thickness 0.000001)
				)
				(justify left)
			)
		)
		(duplicate_pad_numbers_are_jumpers no)
		(fp_poly
			(pts
				(xy 0.635 1.0668) (xy 0.635 -1.0668) (xy -0.635 -1.0668) (xy -0.635 1.0668)
			)
			(stroke
				(width 0)
				(type default)
			)
			(fill no)
			(layer "F.CrtYd")
		)
		(fp_line
			(start -0.254 -0.508)
			(end 0.254 -0.508)
			(stroke
				(width 0.0254)
				(type default)
			)
			(layer "F.Fab")
		)
		(fp_line
			(start -0.254 0.508)
			(end -0.254 -0.508)
			(stroke
				(width 0.0254)
				(type default)
			)
			(layer "F.Fab")
		)
		(fp_line
			(start 0.254 -0.508)
			(end 0.254 0.508)
			(stroke
				(width 0.0254)
				(type default)
			)
			(layer "F.Fab")
		)
		(fp_line
			(start 0.254 0.508)
			(end -0.254 0.508)
			(stroke
				(width 0.0254)
				(type default)
			)
			(layer "F.Fab")
		)
		(pad "1" smd rect
			(at 0 -0.4191)
			(size 0.508 0.5334)
			(layers "F.Cu" "F.Mask" "F.Paste")
			(net "EXT_3.3V")
		)
		(pad "2" smd rect
			(at 0 0.4191)
			(size 0.508 0.5334)
			(layers "F.Cu" "F.Mask" "F.Paste")
			(net "CPLD_NIC_MEZZ_ID0")
		)
		(zone
			(layer "F.Cu")
			(hatch none 0.5)
			(connect_pads
				(clearance 0)
			)
			(min_thickness 0.25)
			(keepout
				(tracks not_allowed)
				(vias allowed)
				(pads allowed)
				(copperpour not_allowed)
				(footprints allowed)
			)
			(placement
				(enabled no)
				(sheetname "")
			)
			(fill
				(thermal_gap 0.5)
				(thermal_bridge_width 0.5)
				(island_removal_mode 0)
			)
			(polygon
				(pts
					(xy 16.5354 1.3716) (xy 16.5354 1.4224) (xy 16.4846 1.4224) (xy 16.4846 1.3716)
				)
			)
		)
	)
	(footprint ""
		(layer "F.Cu")
		(at 77.051002 19.055994)
		(property "Reference" "V_A-DQ22"
			(at 0 0 0)
			(layer "F.SilkS")
			(hide yes)
			(effects
				(font
					(size 1.27 1.27)
				)
			)
		)
		(property "Value" ""
			(at 0 0 0)
			(layer "F.Fab")
			(effects
				(font
					(size 1.27 1.27)
				)
			)
		)
		(duplicate_pad_numbers_are_jumpers no)
		(pad "1" thru_hole circle
			(at 0 0)
			(size 0.762 0.762)
			(drill 0.20574)
			(layers "*.Cu" "*.Mask")
			(remove_unused_layers no)
			(net "DDR0_32A_DQ22")
			(clearance 0.127)
			(thermal_gap 0.127)
			(padstack
				(mode front_inner_back)
				(layer "Inner"
					(shape circle)
					(size 0.4572 0.4572)
					(clearance 0.1143)
				)
				(layer "B.Cu"
					(shape circle)
					(size 0.4572 0.4572)
					(clearance 0.1143)
				)
			)
		)
	)
	(footprint ""
		(layer "F.Cu")
		(at 77.597 10.922 180)
		(property "Reference" "C263"
			(at -0.15367 -3.81 90)
			(unlocked yes)
			(layer "F.SilkS")
			(effects
				(font
					(size 0.7874 0.5842)
					(thickness 0.127)
				)
				(justify left)
			)
		)
		(property "Value" "1UF"
			(at -0.091846 0.2921 270)
			(unlocked yes)
			(layer "F.Fab")
			(hide yes)
			(effects
				(font
					(size 0.7874 0.5842)
					(thickness 0.2032)
				)
				(justify left)
			)
		)
		(property "Device Type" "CAPC0028"
			(at -0.091846 0.2921 270)
			(unlocked yes)
			(layer "F.Fab")
			(hide yes)
			(effects
				(font
					(size 0.7874 0.5842)
					(thickness 0.2032)
				)
				(justify left)
			)
		)
		(duplicate_pad_numbers_are_jumpers no)
		(fp_poly
			(pts
				(xy 0.635 1.0668) (xy 0.635 -1.0668) (xy -0.635 -1.0668) (xy -0.635 1.0668)
			)
			(stroke
				(width 0)
				(type default)
			)
			(fill no)
			(layer "F.CrtYd")
		)
		(fp_line
			(start 0.254 0.508)
			(end -0.254 0.508)
			(stroke
				(width 0.0254)
				(type default)
			)
			(layer "F.Fab")
		)
		(fp_line
			(start 0.254 -0.508)
			(end 0.254 0.508)
			(stroke
				(width 0.0254)
				(type default)
			)
			(layer "F.Fab")
		)
		(fp_line
			(start -0.254 0.508)
			(end -0.254 -0.508)
			(stroke
				(width 0.0254)
				(type default)
			)
			(layer "F.Fab")
		)
		(fp_line
			(start -0.254 -0.508)
			(end 0.254 -0.508)
			(stroke
				(width 0.0254)
				(type default)
			)
			(layer "F.Fab")
		)
		(pad "1" smd rect
			(at 0 -0.4191 180)
			(size 0.508 0.5334)
			(layers "F.Cu" "F.Mask" "F.Paste")
			(net "DDR0_32A_VREF1B")
		)
		(pad "2" smd rect
			(at 0 0.4191 180)
			(size 0.508 0.5334)
			(layers "F.Cu" "F.Mask" "F.Paste")
			(net "GND")
		)
		(zone
			(layer "F.Cu")
			(hatch none 0.5)
			(connect_pads
				(clearance 0)
			)
			(min_thickness 0.25)
			(keepout
				(tracks not_allowed)
				(vias allowed)
				(pads allowed)
				(copperpour not_allowed)
				(footprints allowed)
			)
			(placement
				(enabled no)
				(sheetname "")
			)
			(fill
				(thermal_gap 0.5)
				(thermal_bridge_width 0.5)
				(island_removal_mode 0)
			)
			(polygon
				(pts
					(xy 77.5716 10.9474) (xy 77.5716 10.8966) (xy 77.6224 10.8966) (xy 77.6224 10.9474)
				)
			)
		)
	)
	(footprint ""
		(layer "F.Cu")
		(at 78.994 4.191 90)
		(property "Reference" "R289"
			(at -0.78867 -1.524 0)
			(unlocked yes)
			(layer "F.SilkS")
			(effects
				(font
					(size 0.7874 0.5842)
					(thickness 0.127)
				)
				(justify left)
			)
		)
		(property "Value" "100"
			(at -0.148158 1.3462 180)
			(unlocked yes)
			(layer "F.Fab")
			(hide yes)
			(effects
				(font
					(size 1.27 0.9652)
					(thickness 0.000001)
				)
				(justify left)
			)
		)
		(property "Device Type" "REST4030"
			(at -0.148158 1.3462 180)
			(unlocked yes)
			(layer "F.Fab")
			(hide yes)
			(effects
				(font
					(size 1.27 0.9652)
					(thickness 0.000001)
				)
				(justify left)
			)
		)
		(duplicate_pad_numbers_are_jumpers no)
		(fp_poly
			(pts
				(xy 0.635 1.0668) (xy 0.635 -1.0668) (xy -0.635 -1.0668) (xy -0.635 1.0668)
			)
			(stroke
				(width 0)
				(type default)
			)
			(fill no)
			(layer "F.CrtYd")
		)
		(fp_line
			(start 0.254 -0.508)
			(end 0.254 0.508)
			(stroke
				(width 0.0254)
				(type default)
			)
			(layer "F.Fab")
		)
		(fp_line
			(start -0.254 -0.508)
			(end 0.254 -0.508)
			(stroke
				(width 0.0254)
				(type default)
			)
			(layer "F.Fab")
		)
		(fp_line
			(start 0.254 0.508)
			(end -0.254 0.508)
			(stroke
				(width 0.0254)
				(type default)
			)
			(layer "F.Fab")
		)
		(fp_line
			(start -0.254 0.508)
			(end -0.254 -0.508)
			(stroke
				(width 0.0254)
				(type default)
			)
			(layer "F.Fab")
		)
		(pad "1" smd rect
			(at 0 -0.4191 90)
			(size 0.508 0.5334)
			(layers "F.Cu" "F.Mask" "F.Paste")
			(net "GND")
		)
		(pad "2" smd rect
			(at 0 0.4191 90)
			(size 0.508 0.5334)
			(layers "F.Cu" "F.Mask" "F.Paste")
			(net "DDR0_32A_VREF0B")
		)
		(zone
			(layer "F.Cu")
			(hatch none 0.5)
			(connect_pads
				(clearance 0)
			)
			(min_thickness 0.25)
			(keepout
				(tracks not_allowed)
				(vias allowed)
				(pads allowed)
				(copperpour not_allowed)
				(footprints allowed)
			)
			(placement
				(enabled no)
				(sheetname "")
			)
			(fill
				(thermal_gap 0.5)
				(thermal_bridge_width 0.5)
				(island_removal_mode 0)
			)
			(polygon
				(pts
					(xy 78.9686 4.1656) (xy 79.0194 4.1656) (xy 79.0194 4.2164) (xy 78.9686 4.2164)
				)
			)
		)
	)
	(footprint ""
		(layer "F.Cu")
		(at 35.941 7.493 90)
		(property "Reference" "R132"
			(at 0 0 90)
			(layer "F.SilkS")
			(hide yes)
			(effects
				(font
					(size 1.27 1.27)
				)
			)
		)
		(property "Value" "0"
			(at -0.148158 1.3462 180)
			(unlocked yes)
			(layer "F.Fab")
			(hide yes)
			(effects
				(font
					(size 1.27 0.9652)
					(thickness 0.000001)
				)
				(justify left)
			)
		)
		(property "Device Type" "REST1111"
			(at -0.148158 1.3462 180)
			(unlocked yes)
			(layer "F.Fab")
			(hide yes)
			(effects
				(font
					(size 1.27 0.9652)
					(thickness 0.000001)
				)
				(justify left)
			)
		)
		(duplicate_pad_numbers_are_jumpers no)
		(fp_poly
			(pts
				(xy 0.635 1.0668) (xy 0.635 -1.0668) (xy -0.635 -1.0668) (xy -0.635 1.0668)
			)
			(stroke
				(width 0)
				(type default)
			)
			(fill no)
			(layer "F.CrtYd")
		)
		(fp_line
			(start 0.254 -0.508)
			(end 0.254 0.508)
			(stroke
				(width 0.0254)
				(type default)
			)
			(layer "F.Fab")
		)
		(fp_line
			(start -0.254 -0.508)
			(end 0.254 -0.508)
			(stroke
				(width 0.0254)
				(type default)
			)
			(layer "F.Fab")
		)
		(fp_line
			(start 0.254 0.508)
			(end -0.254 0.508)
			(stroke
				(width 0.0254)
				(type default)
			)
			(layer "F.Fab")
		)
		(fp_line
			(start -0.254 0.508)
			(end -0.254 -0.508)
			(stroke
				(width 0.0254)
				(type default)
			)
			(layer "F.Fab")
		)
		(pad "1" smd rect
			(at 0 -0.4191 90)
			(size 0.508 0.5334)
			(layers "F.Cu" "F.Mask" "F.Paste")
			(net "3N2290")
		)
		(pad "2" smd rect
			(at 0 0.4191 90)
			(size 0.508 0.5334)
			(layers "F.Cu" "F.Mask" "F.Paste")
			(net "NFP_SERDES012_SYSCLK_IN_N")
		)
		(zone
			(layer "F.Cu")
			(hatch none 0.5)
			(connect_pads
				(clearance 0)
			)
			(min_thickness 0.25)
			(keepout
				(tracks not_allowed)
				(vias allowed)
				(pads allowed)
				(copperpour not_allowed)
				(footprints allowed)
			)
			(placement
				(enabled no)
				(sheetname "")
			)
			(fill
				(thermal_gap 0.5)
				(thermal_bridge_width 0.5)
				(island_removal_mode 0)
			)
			(polygon
				(pts
					(xy 35.9156 7.4676) (xy 35.9664 7.4676) (xy 35.9664 7.5184) (xy 35.9156 7.5184)
				)
			)
		)
	)
	(footprint ""
		(layer "F.Cu")
		(at 74.2442 42.164 -90)
		(property "Reference" "TP53"
			(at -1.016 0.35433 90)
			(unlocked yes)
			(layer "F.SilkS")
			(effects
				(font
					(size 0.7874 0.5842)
					(thickness 0.127)
				)
				(justify left)
			)
		)
		(property "Value" "*"
			(at -0.4826 -0.14732 270)
			(unlocked yes)
			(layer "F.Fab")
			(hide yes)
			(effects
				(font
					(size 1.27 0.9652)
					(thickness 0.000001)
				)
				(justify left)
			)
		)
		(property "Device Type" "TP_SMALL"
			(at -0.4826 -0.14732 270)
			(unlocked yes)
			(layer "F.Fab")
			(hide yes)
			(effects
				(font
					(size 1.27 0.9652)
					(thickness 0.000001)
				)
				(justify left)
			)
		)
		(duplicate_pad_numbers_are_jumpers no)
		(fp_line
			(start -0.8636 0.8636)
			(end 0.8636 0.8636)
			(stroke
				(width 0.1524)
				(type default)
			)
			(layer "F.SilkS")
		)
		(fp_line
			(start 0.8636 0.8636)
			(end 0.8636 -0.8636)
			(stroke
				(width 0.1524)
				(type default)
			)
			(layer "F.SilkS")
		)
		(fp_line
			(start -0.8636 -0.8636)
			(end -0.8636 0.8636)
			(stroke
				(width 0.1524)
				(type default)
			)
			(layer "F.SilkS")
		)
		(fp_line
			(start 0.8636 -0.8636)
			(end -0.8636 -0.8636)
			(stroke
				(width 0.1524)
				(type default)
			)
			(layer "F.SilkS")
		)
		(fp_poly
			(pts
				(xy -0.635 -0.635) (xy -0.635 0.635) (xy 0.635 0.635) (xy 0.635 -0.635)
			)
			(stroke
				(width 0)
				(type default)
			)
			(fill no)
			(layer "F.CrtYd")
		)
		(pad "1" smd rect
			(at 0 0 270)
			(size 1.27 1.27)
			(layers "F.Cu" "F.Mask" "F.Paste")
			(net "GND")
		)
	)
	(footprint ""
		(layer "F.Cu")
		(at 26.67 43.561)
		(property "Reference" "C81"
			(at 0 0 0)
			(layer "F.SilkS")
			(hide yes)
			(effects
				(font
					(size 1.27 1.27)
				)
			)
		)
		(property "Value" "680PF"
			(at -0.091846 0.2921 90)
			(unlocked yes)
			(layer "F.Fab")
			(hide yes)
			(effects
				(font
					(size 0.7874 0.5842)
					(thickness 0.2032)
				)
				(justify left)
			)
		)
		(property "Device Type" "CAPC0012"
			(at -0.091846 0.2921 90)
			(unlocked yes)
			(layer "F.Fab")
			(hide yes)
			(effects
				(font
					(size 0.7874 0.5842)
					(thickness 0.2032)
				)
				(justify left)
			)
		)
		(duplicate_pad_numbers_are_jumpers no)
		(fp_poly
			(pts
				(xy 0.635 1.0668) (xy 0.635 -1.0668) (xy -0.635 -1.0668) (xy -0.635 1.0668)
			)
			(stroke
				(width 0)
				(type default)
			)
			(fill no)
			(layer "F.CrtYd")
		)
		(fp_line
			(start -0.254 -0.508)
			(end 0.254 -0.508)
			(stroke
				(width 0.0254)
				(type default)
			)
			(layer "F.Fab")
		)
		(fp_line
			(start -0.254 0.508)
			(end -0.254 -0.508)
			(stroke
				(width 0.0254)
				(type default)
			)
			(layer "F.Fab")
		)
		(fp_line
			(start 0.254 -0.508)
			(end 0.254 0.508)
			(stroke
				(width 0.0254)
				(type default)
			)
			(layer "F.Fab")
		)
		(fp_line
			(start 0.254 0.508)
			(end -0.254 0.508)
			(stroke
				(width 0.0254)
				(type default)
			)
			(layer "F.Fab")
		)
		(pad "1" smd rect
			(at 0 -0.4191)
			(size 0.508 0.5334)
			(layers "F.Cu" "F.Mask" "F.Paste")
			(net "10N2383")
		)
		(pad "2" smd rect
			(at 0 0.4191)
			(size 0.508 0.5334)
			(layers "F.Cu" "F.Mask" "F.Paste")
			(net "GND")
		)
		(zone
			(layer "F.Cu")
			(hatch none 0.5)
			(connect_pads
				(clearance 0)
			)
			(min_thickness 0.25)
			(keepout
				(tracks not_allowed)
				(vias allowed)
				(pads allowed)
				(copperpour not_allowed)
				(footprints allowed)
			)
			(placement
				(enabled no)
				(sheetname "")
			)
			(fill
				(thermal_gap 0.5)
				(thermal_bridge_width 0.5)
				(island_removal_mode 0)
			)
			(polygon
				(pts
					(xy 26.6954 43.5356) (xy 26.6954 43.5864) (xy 26.6446 43.5864) (xy 26.6446 43.5356)
				)
			)
		)
	)
	(footprint ""
		(layer "F.Cu")
		(at 49.53 50.038 180)
		(property "Reference" "R121"
			(at 0 0 180)
			(layer "F.SilkS")
			(hide yes)
			(effects
				(font
					(size 1.27 1.27)
				)
			)
		)
		(property "Value" "100K"
			(at -0.148158 1.3462 270)
			(unlocked yes)
			(layer "F.Fab")
			(hide yes)
			(effects
				(font
					(size 1.27 0.9652)
					(thickness 0.000001)
				)
				(justify left)
			)
		)
		(property "Device Type" "REST0001"
			(at -0.148158 1.3462 270)
			(unlocked yes)
			(layer "F.Fab")
			(hide yes)
			(effects
				(font
					(size 1.27 0.9652)
					(thickness 0.000001)
				)
				(justify left)
			)
		)
		(duplicate_pad_numbers_are_jumpers no)
		(fp_poly
			(pts
				(xy 0.635 1.0668) (xy 0.635 -1.0668) (xy -0.635 -1.0668) (xy -0.635 1.0668)
			)
			(stroke
				(width 0)
				(type default)
			)
			(fill no)
			(layer "F.CrtYd")
		)
		(fp_line
			(start 0.254 0.508)
			(end -0.254 0.508)
			(stroke
				(width 0.0254)
				(type default)
			)
			(layer "F.Fab")
		)
		(fp_line
			(start 0.254 -0.508)
			(end 0.254 0.508)
			(stroke
				(width 0.0254)
				(type default)
			)
			(layer "F.Fab")
		)
		(fp_line
			(start -0.254 0.508)
			(end -0.254 -0.508)
			(stroke
				(width 0.0254)
				(type default)
			)
			(layer "F.Fab")
		)
		(fp_line
			(start -0.254 -0.508)
			(end 0.254 -0.508)
			(stroke
				(width 0.0254)
				(type default)
			)
			(layer "F.Fab")
		)
		(pad "1" smd rect
			(at 0 -0.4191 180)
			(size 0.508 0.5334)
			(layers "F.Cu" "F.Mask" "F.Paste")
			(net "EXT_3.3V_THRESHOLD")
		)
		(pad "2" smd rect
			(at 0 0.4191 180)
			(size 0.508 0.5334)
			(layers "F.Cu" "F.Mask" "F.Paste")
			(net "EXT_3.3V_PGOOD")
		)
		(zone
			(layer "F.Cu")
			(hatch none 0.5)
			(connect_pads
				(clearance 0)
			)
			(min_thickness 0.25)
			(keepout
				(tracks not_allowed)
				(vias allowed)
				(pads allowed)
				(copperpour not_allowed)
				(footprints allowed)
			)
			(placement
				(enabled no)
				(sheetname "")
			)
			(fill
				(thermal_gap 0.5)
				(thermal_bridge_width 0.5)
				(island_removal_mode 0)
			)
			(polygon
				(pts
					(xy 49.5046 50.0634) (xy 49.5046 50.0126) (xy 49.5554 50.0126) (xy 49.5554 50.0634)
				)
			)
		)
	)
)
